# T6G (Grand Teton) — schematic netlist excerpt (pin names and nets, part order shuffled) for the footprints in the layout excerpt that follows; sources: Cadence DE-HDL packaged netlist, KiCad conversion of 04192023_DAF0TMB3IC0_F0TG_MB_C_brd_V02_OCP.brd

R2344  Q_RES  4.7K 5% CHIP  pkg 0402LF  page 85 : A = P3V3_AUX ; B = PWRGD_P5V_AUX_R1
C6516  Q_CAP_DIFFBUS  DIFF BUS_0.22UF 6.3V 20% X6S  pkg C0201  page 275 : \1\ = P5E_CPU0_P0_TX_BUF_C_DN<7> ; \2\ = P5E_CPU0_P0_TX_BUF_DN<7>

Q69  MOSFET_NCH_DUAL  PJT138K IC  pkg SOT363XD  page 127
  S1  = GND
  G1  = RST_BMC_FROM_SWB_N
  D2  = RST_BMC_FROM_SWB_ISO_N
  S2  = GND
  G2  = RST_BMC_FROM_SWB
  D1  = RST_BMC_FROM_SWB

(kicad_pcb
	(version 20260206)
	(generator "pcbnew")
	(generator_version "10.0")
	(general
		(thickness 1.6)
		(legacy_teardrops no)
	)
	(paper "A4")
	(title_block
		(title "04192023_DAF0TMB3IC0_F0TG_MB_C_brd_V02_OCP.brd")
		(comment 1 "Grand Teton / footprints 542-544 of 8354")
	)
	(layers
		(0 "F.Cu" signal "TOP")
		(4 "In1.Cu" signal "GND")
		(6 "In2.Cu" signal "IN1")
		(8 "In3.Cu" signal "GND1")
		(10 "In4.Cu" signal "IN2")
		(12 "In5.Cu" signal "GND2")
		(14 "In6.Cu" signal "IN3")
		(16 "In7.Cu" signal "GND3")
		(18 "In8.Cu" signal "VCC")
		(20 "In9.Cu" signal "VCC1")
		(22 "In10.Cu" signal "GND4")
		(24 "In11.Cu" signal "IN4")
		(26 "In12.Cu" signal "GND5")
		(28 "In13.Cu" signal "IN5")
		(30 "In14.Cu" signal "GND6")
		(32 "In15.Cu" signal "IN6")
		(34 "In16.Cu" signal "GND7")
		(2 "B.Cu" signal "BOTTOM")
		(9 "F.Adhes" user "F.Adhesive")
		(11 "B.Adhes" user "B.Adhesive")
		(13 "F.Paste" user "Package Geometry/Pastemask Top")
		(15 "B.Paste" user "Package Geometry/Pastemask Bottom")
		(5 "F.SilkS" user "Ref Des/Silkscreen Top")
		(7 "B.SilkS" user "Ref Des/Silkscreen Bottom")
		(1 "F.Mask" user "Board Geometry/Soldermask Top")
		(3 "B.Mask" user "Board Geometry/Soldermask Bottom")
		(17 "Dwgs.User" user "User.Drawings")
		(19 "Cmts.User" user "User.Comments")
		(21 "Eco1.User" user "User.Eco1")
		(23 "Eco2.User" user "User.Eco2")
		(25 "Edge.Cuts" user "Board Geometry/Outline")
		(27 "Margin" user)
		(31 "F.CrtYd" user "Package Geometry/Place Bound Top")
		(29 "B.CrtYd" user "Package Geometry/Place Bound Bottom")
		(35 "F.Fab" user "Ref Des/Assembly Top")
		(33 "B.Fab" user "Ref Des/Assembly Bottom")
	)
	(footprint ""
		(layer "F.Cu")
		(at 399.197322 -134.92988)
		(property "Reference" "R2344"
			(at 0 0 0)
			(layer "F.SilkS")
			(hide yes)
			(effects
				(font
					(size 1.27 1.27)
				)
			)
		)
		(property "Value" ""
			(at 0 0 0)
			(layer "F.Fab")
			(effects
				(font
					(size 1.27 1.27)
				)
			)
		)
		(duplicate_pad_numbers_are_jumpers no)
		(fp_line
			(start -0.7874 -0.4064)
			(end 0.7874 -0.4064)
			(stroke
				(width 0.1524)
				(type default)
			)
			(layer "F.SilkS")
		)
		(fp_line
			(start -0.7874 0.4064)
			(end -0.7874 -0.4064)
			(stroke
				(width 0.1524)
				(type default)
			)
			(layer "F.SilkS")
		)
		(fp_line
			(start 0.7874 -0.4064)
			(end 0.7874 0.4064)
			(stroke
				(width 0.1524)
				(type default)
			)
			(layer "F.SilkS")
		)
		(fp_line
			(start 0.7874 0.4064)
			(end -0.7874 0.4064)
			(stroke
				(width 0.1524)
				(type default)
			)
			(layer "F.SilkS")
		)
		(fp_line
			(start -0.67945 -0.305054)
			(end -0.12065 -0.305054)
			(stroke
				(width 0.1)
				(type default)
			)
			(layer "F.Fab")
		)
		(fp_line
			(start -0.67945 0.3048)
			(end -0.67945 -0.305054)
			(stroke
				(width 0.1)
				(type default)
			)
			(layer "F.Fab")
		)
		(fp_line
			(start -0.12065 -0.305054)
			(end -0.12065 -0.2794)
			(stroke
				(width 0.1)
				(type default)
			)
			(layer "F.Fab")
		)
		(fp_line
			(start -0.12065 -0.2794)
			(end 0.12065 -0.2794)
			(stroke
				(width 0.1)
				(type default)
			)
			(layer "F.Fab")
		)
		(fp_line
			(start -0.12065 0.2794)
			(end -0.12065 0.3048)
			(stroke
				(width 0.1)
				(type default)
			)
			(layer "F.Fab")
		)
		(fp_line
			(start -0.12065 0.3048)
			(end -0.67945 0.3048)
			(stroke
				(width 0.1)
				(type default)
			)
			(layer "F.Fab")
		)
		(fp_line
			(start 0.120396 0.2794)
			(end -0.12065 0.2794)
			(stroke
				(width 0.1)
				(type default)
			)
			(layer "F.Fab")
		)
		(fp_line
			(start 0.120396 0.3048)
			(end 0.120396 0.2794)
			(stroke
				(width 0.1)
				(type default)
			)
			(layer "F.Fab")
		)
		(fp_line
			(start 0.12065 -0.3048)
			(end 0.67945 -0.3048)
			(stroke
				(width 0.1)
				(type default)
			)
			(layer "F.Fab")
		)
		(fp_line
			(start 0.12065 -0.2794)
			(end 0.12065 -0.3048)
			(stroke
				(width 0.1)
				(type default)
			)
			(layer "F.Fab")
		)
		(fp_line
			(start 0.67945 -0.3048)
			(end 0.67945 0.3048)
			(stroke
				(width 0.1)
				(type default)
			)
			(layer "F.Fab")
		)
		(fp_line
			(start 0.67945 0.3048)
			(end 0.120396 0.3048)
			(stroke
				(width 0.1)
				(type default)
			)
			(layer "F.Fab")
		)
		(pad "1" smd circle
			(at -0.40005 0)
			(size 0 0)
			(layers "F.Cu" "F.Mask" "F.Paste")
			(net "P3V3_AUX")
		)
		(pad "2" smd circle
			(at 0.40005 0)
			(size 0 0)
			(layers "F.Cu" "F.Mask" "F.Paste")
			(net "PWRGD_P5V_AUX_R1")
		)
	)
	(footprint ""
		(layer "F.Cu")
		(at 423.35704 -439.284872)
		(property "Reference" "Q69"
			(at -1.239266 -1.871726 0)
			(unlocked yes)
			(layer "F.SilkS")
			(effects
				(font
					(size 0.7874 0.5842)
					(thickness 0.1524)
				)
				(justify left)
			)
		)
		(property "Value" ""
			(at 0 0 0)
			(layer "F.Fab")
			(effects
				(font
					(size 1.27 1.27)
				)
			)
		)
		(duplicate_pad_numbers_are_jumpers no)
		(fp_line
			(start -1.332738 -1.100074)
			(end -0.4826 -1.100074)
			(stroke
				(width 0.1524)
				(type default)
			)
			(layer "F.SilkS")
		)
		(fp_line
			(start -1.332738 1.100074)
			(end -1.332738 -1.100074)
			(stroke
				(width 0.1524)
				(type default)
			)
			(layer "F.SilkS")
		)
		(fp_line
			(start -0.4826 -1.100074)
			(end 0 -0.541274)
			(stroke
				(width 0.1524)
				(type default)
			)
			(layer "F.SilkS")
		)
		(fp_line
			(start 0 -0.541274)
			(end 0.4826 -1.100074)
			(stroke
				(width 0.1524)
				(type default)
			)
			(layer "F.SilkS")
		)
		(fp_line
			(start 0.4826 -1.100074)
			(end 1.332738 -1.100074)
			(stroke
				(width 0.1524)
				(type default)
			)
			(layer "F.SilkS")
		)
		(fp_line
			(start 1.332738 -1.100074)
			(end 1.332738 1.100074)
			(stroke
				(width 0.1524)
				(type default)
			)
			(layer "F.SilkS")
		)
		(fp_line
			(start 1.332738 1.100074)
			(end -1.332738 1.100074)
			(stroke
				(width 0.1524)
				(type default)
			)
			(layer "F.SilkS")
		)
		(fp_poly
			(pts
				(xy -1.533144 -0.649986) (xy -2.2352 -0.298958) (xy -2.2352 -1.001014)
			)
			(stroke
				(width 0)
				(type default)
			)
			(fill yes)
			(layer "F.SilkS")
		)
		(fp_line
			(start -0.674878 -1.100074)
			(end 0.674878 -1.100074)
			(stroke
				(width 0.1)
				(type default)
			)
			(layer "F.Fab")
		)
		(fp_line
			(start -0.674878 1.100074)
			(end -0.674878 -1.100074)
			(stroke
				(width 0.1)
				(type default)
			)
			(layer "F.Fab")
		)
		(fp_line
			(start 0.674878 -1.100074)
			(end 0.674878 1.100074)
			(stroke
				(width 0.1)
				(type default)
			)
			(layer "F.Fab")
		)
		(fp_line
			(start 0.674878 1.100074)
			(end -0.674878 1.100074)
			(stroke
				(width 0.1)
				(type default)
			)
			(layer "F.Fab")
		)
		(fp_poly
			(pts
				(xy -2.2352 -0.298958) (xy -2.2352 -1.001014) (xy -1.533144 -0.649986)
			)
			(stroke
				(width 0)
				(type default)
			)
			(fill yes)
			(layer "F.Fab")
		)
		(pad "1" smd rect
			(at -0.94996 -0.649986 90)
			(size 0.4318 0.508)
			(layers "F.Cu" "F.Mask" "F.Paste")
			(net "GND")
		)
		(pad "2" smd rect
			(at -0.94996 0 90)
			(size 0.4318 0.508)
			(layers "F.Cu" "F.Mask" "F.Paste")
			(net "RST_BMC_FROM_SWB_N")
		)
		(pad "3" smd rect
			(at -0.94996 0.649986 90)
			(size 0.4318 0.508)
			(layers "F.Cu" "F.Mask" "F.Paste")
			(net "RST_BMC_FROM_SWB_ISO_N")
		)
		(pad "4" smd rect
			(at 0.94996 0.649986 90)
			(size 0.4318 0.508)
			(layers "F.Cu" "F.Mask" "F.Paste")
			(net "GND")
		)
		(pad "5" smd rect
			(at 0.94996 0 90)
			(size 0.4318 0.508)
			(layers "F.Cu" "F.Mask" "F.Paste")
			(net "RST_BMC_FROM_SWB")
		)
		(pad "6" smd rect
			(at 0.94996 -0.649986 90)
			(size 0.4318 0.508)
			(layers "F.Cu" "F.Mask" "F.Paste")
			(net "RST_BMC_FROM_SWB")
		)
	)
	(footprint ""
		(layer "F.Cu")
		(at 325.211186 -416.899344 -90)
		(property "Reference" "C6516"
			(at 0 0 270)
			(layer "F.SilkS")
			(hide yes)
			(effects
				(font
					(size 1.27 1.27)
				)
			)
		)
		(property "Value" ""
			(at 0 0 270)
			(layer "F.Fab")
			(effects
				(font
					(size 1.27 1.27)
				)
			)
		)
		(duplicate_pad_numbers_are_jumpers no)
		(fp_line
			(start -0.299974 0.150114)
			(end -0.299974 -0.150114)
			(stroke
				(width 0.1)
				(type default)
			)
			(layer "F.Fab")
		)
		(fp_line
			(start 0.299974 0.150114)
			(end -0.299974 0.150114)
			(stroke
				(width 0.1)
				(type default)
			)
			(layer "F.Fab")
		)
		(fp_line
			(start -0.299974 -0.150114)
			(end 0.299974 -0.150114)
			(stroke
				(width 0.1)
				(type default)
			)
			(layer "F.Fab")
		)
		(fp_line
			(start 0.299974 -0.150114)
			(end 0.299974 0.150114)
			(stroke
				(width 0.1)
				(type default)
			)
			(layer "F.Fab")
		)
		(pad "1" smd rect
			(at -0.2667 0 270)
			(size 0.3048 0.381)
			(layers "F.Cu" "F.Mask" "F.Paste")
			(net "P5E_CPU0_P0_TX_BUF_C_DN<7>")
		)
		(pad "2" smd rect
			(at 0.2667 0 270)
			(size 0.3048 0.381)
			(layers "F.Cu" "F.Mask" "F.Paste")
			(net "P5E_CPU0_P0_TX_BUF_DN<7>")
		)
	)
)
